# TIMECARD (Time Appliance Project (Time Card)) — schematic netlist excerpt (pin names and nets, part order shuffled) for the footprints in the layout excerpt that follows; sources: Cadence DE-HDL packaged netlist, KiCad conversion of R4006-B0001-02_R01.brd

R438  RESISTOR  10KOHM 1%  pkg SMC_0402R_H016  page 13 : \1\ = FPGA_IN_MAC_PPS_OUTN ; \2\ = XP2R5V_FPGA
TP59  TP_PIONT  pkg TP010CT020B030_PTH  page 25 : \1\ = XP3R3V_EN

(kicad_pcb
	(version 20260206)
	(generator "pcbnew")
	(generator_version "10.0")
	(general
		(thickness 1.6)
		(legacy_teardrops no)
	)
	(paper "A4")
	(title_block
		(title "timecard-production-celestica-r4006 — R4006-B0001-02_R01.brd")
		(comment 1 "Time Appliance Project (Time Card) / footprints 216-217 of 1113")
	)
	(layers
		(0 "F.Cu" signal "TOP")
		(4 "In1.Cu" signal "L02_GND1")
		(6 "In2.Cu" signal "L03_SIG1")
		(8 "In3.Cu" signal "L04_GND2")
		(10 "In4.Cu" signal "L05_VCC1")
		(12 "In5.Cu" signal "L06_VCC2")
		(14 "In6.Cu" signal "L07_GND3")
		(16 "In7.Cu" signal "L08_SIG2")
		(18 "In8.Cu" signal "L09_GND4")
		(2 "B.Cu" signal "BOTTOM")
		(9 "F.Adhes" user "F.Adhesive")
		(11 "B.Adhes" user "B.Adhesive")
		(13 "F.Paste" user "Package Geometry/Pastemask Top")
		(15 "B.Paste" user "Package Geometry/Pastemask Bottom")
		(5 "F.SilkS" user "Ref Des/Silkscreen Top")
		(7 "B.SilkS" user "Ref Des/Silkscreen Bottom")
		(1 "F.Mask" user "Board Geometry/Soldermask Top")
		(3 "B.Mask" user "Board Geometry/Soldermask Bottom")
		(17 "Dwgs.User" user "User.Drawings")
		(19 "Cmts.User" user "User.Comments")
		(21 "Eco1.User" user "User.Eco1")
		(23 "Eco2.User" user "User.Eco2")
		(25 "Edge.Cuts" user "Board Geometry/Outline")
		(27 "Margin" user)
		(31 "F.CrtYd" user "Package Geometry/Place Bound Top")
		(29 "B.CrtYd" user "Package Geometry/Place Bound Bottom")
		(35 "F.Fab" user "Ref Des/Assembly Top")
		(33 "B.Fab" user "Ref Des/Assembly Bottom")
	)
	(footprint ""
		(layer "F.Cu")
		(at 116.459 -29.464 -90)
		(property "Reference" "R438"
			(at 2.794 -0.80137 90)
			(unlocked yes)
			(layer "F.SilkS")
			(effects
				(font
					(size 0.7874 0.5842)
					(thickness 0.1524)
				)
			)
		)
		(property "Value" "VAL*"
			(at 0.02032 2.13233 270)
			(unlocked yes)
			(layer "F.Fab")
			(hide yes)
			(effects
				(font
					(size 0.7874 0.5842)
					(thickness 0.1524)
				)
			)
		)
		(property "Tolerance" "TOL*"
			(at 0.044704 3.05435 270)
			(unlocked yes)
			(layer "Cmts.User")
			(hide yes)
			(effects
				(font
					(size 0.7874 0.5842)
					(thickness 0.1524)
				)
			)
		)
		(property "User Part Number" "PARTNUM*"
			(at 0.02032 4.024884 270)
			(unlocked yes)
			(layer "Cmts.User")
			(hide yes)
			(effects
				(font
					(size 0.7874 0.5842)
					(thickness 0.1524)
				)
			)
		)
		(property "Device Type" "RESISTOR-G155-11002-01,10KOHM,A"
			(at 0.008382 1.210564 270)
			(unlocked yes)
			(layer "F.Fab")
			(hide yes)
			(effects
				(font
					(size 0.7874 0.5842)
					(thickness 0.1524)
				)
			)
		)
		(duplicate_pad_numbers_are_jumpers no)
		(fp_line
			(start -1.143 0.5588)
			(end 1.143 0.5588)
			(stroke
				(width 0.1)
				(type default)
			)
			(layer "F.SilkS")
		)
		(fp_line
			(start 1.143 0.5588)
			(end 1.143 -0.5588)
			(stroke
				(width 0.1)
				(type default)
			)
			(layer "F.SilkS")
		)
		(fp_line
			(start -1.143 -0.5588)
			(end -1.143 0.5588)
			(stroke
				(width 0.1)
				(type default)
			)
			(layer "F.SilkS")
		)
		(fp_line
			(start 1.143 -0.5588)
			(end -1.143 -0.5588)
			(stroke
				(width 0.1)
				(type default)
			)
			(layer "F.SilkS")
		)
		(fp_poly
			(pts
				(xy -1.143 0.5588) (xy 1.143 0.5588) (xy 1.143 -0.5588) (xy -1.143 -0.5588)
			)
			(stroke
				(width 0)
				(type default)
			)
			(fill no)
			(layer "F.CrtYd")
		)
		(fp_line
			(start -0.508 0.3048)
			(end 0.508 0.3048)
			(stroke
				(width 0.1)
				(type default)
			)
			(layer "F.Fab")
		)
		(fp_line
			(start 0.508 0.3048)
			(end 0.508 -0.3048)
			(stroke
				(width 0.1)
				(type default)
			)
			(layer "F.Fab")
		)
		(fp_line
			(start -0.508 -0.3048)
			(end -0.508 0.3048)
			(stroke
				(width 0.1)
				(type default)
			)
			(layer "F.Fab")
		)
		(fp_line
			(start 0.508 -0.3048)
			(end -0.508 -0.3048)
			(stroke
				(width 0.1)
				(type default)
			)
			(layer "F.Fab")
		)
		(pad "1" smd rect
			(at -0.5334 0 270)
			(size 0.7112 0.6096)
			(layers "F.Cu" "F.Mask" "F.Paste")
			(net "FPGA_IN_MAC_PPS_OUTN")
		)
		(pad "2" smd rect
			(at 0.5334 0 270)
			(size 0.7112 0.6096)
			(layers "F.Cu" "F.Mask" "F.Paste")
			(net "XP2R5V_FPGA")
		)
		(zone
			(layer "F.Cu")
			(hatch none 0.5)
			(connect_pads
				(clearance 0)
			)
			(min_thickness 0.25)
			(keepout
				(tracks allowed)
				(vias not_allowed)
				(pads allowed)
				(copperpour not_allowed)
				(footprints allowed)
			)
			(placement
				(enabled no)
				(sheetname "")
			)
			(fill
				(thermal_gap 0.5)
				(thermal_bridge_width 0.5)
				(island_removal_mode 0)
			)
			(polygon
				(pts
					(xy 116.1542 -29.5402) (xy 116.1542 -29.3878) (xy 116.7638 -29.3878) (xy 116.7638 -29.5402)
				)
			)
		)
		(zone
			(layer "F.Cu")
			(hatch none 0.5)
			(connect_pads
				(clearance 0)
			)
			(min_thickness 0.25)
			(keepout
				(tracks not_allowed)
				(vias allowed)
				(pads allowed)
				(copperpour not_allowed)
				(footprints allowed)
			)
			(placement
				(enabled no)
				(sheetname "")
			)
			(fill
				(thermal_gap 0.5)
				(thermal_bridge_width 0.5)
				(island_removal_mode 0)
			)
			(polygon
				(pts
					(xy 116.1542 -29.5402) (xy 116.1542 -29.3878) (xy 116.7638 -29.3878) (xy 116.7638 -29.5402)
				)
			)
		)
	)
	(footprint ""
		(layer "F.Cu")
		(at 93.726 -105.029 180)
		(property "Reference" "TP59"
			(at -0.8128 -0.16637 0)
			(unlocked yes)
			(layer "F.SilkS")
			(effects
				(font
					(size 0.7874 0.5842)
					(thickness 0.1524)
				)
				(justify left)
			)
		)
		(property "Value" ""
			(at 0 0 180)
			(layer "F.Fab")
			(effects
				(font
					(size 1.27 1.27)
				)
			)
		)
		(property "Device Type" "TP_PIONT-TP010CT020B030_PTH-TPA"
			(at -1.341882 0.996696 180)
			(unlocked yes)
			(layer "F.Fab")
			(hide yes)
			(effects
				(font
					(size 0.7874 0.5842)
					(thickness 0.1524)
				)
				(justify left)
			)
		)
		(duplicate_pad_numbers_are_jumpers no)
		(fp_poly
			(pts
				(arc
					(start -0.889 0)
					(mid 0.889 0)
					(end -0.889 0)
				)
			)
			(stroke
				(width 0)
				(type default)
			)
			(fill no)
			(layer "B.CrtYd")
		)
		(fp_poly
			(pts
				(arc
					(start -0.889 0)
					(mid 0.889 0)
					(end -0.889 0)
				)
			)
			(stroke
				(width 0)
				(type default)
			)
			(fill no)
			(layer "F.CrtYd")
		)
		(pad "1" thru_hole circle
			(at 0 0 180)
			(size 0.508 0.508)
			(drill 0.254)
			(layers "*.Cu" "*.Mask")
			(remove_unused_layers no)
			(net "XP3R3V_EN")
			(clearance 0.1016)
			(padstack
				(mode front_inner_back)
				(layer "Inner"
					(shape circle)
					(size 0.508 0.508)
					(clearance 0.1016)
				)
				(layer "B.Cu"
					(shape circle)
					(size 0.762 0.762)
					(clearance -0.0254)
				)
			)
		)
	)
)
